(kicad_pcb
	(version 20260206)
	(generator "pcbnew")
	(generator_version "10.0")
	(general
		(thickness 1.6)
		(legacy_teardrops no)
	)
	(paper "A4")
	(title_block
		(title "03242023_DA0F0TMBIJ0_F0T_Motherboard_J_brd_V01_OCP.brd")
		(comment 1 "Grand Teton / footprints 3528-3534 of 6105")
	)
	(layers
		(0 "F.Cu" signal "TOP")
		(4 "In1.Cu" signal "GND")
		(6 "In2.Cu" signal "IN1")
		(8 "In3.Cu" signal "GND1")
		(10 "In4.Cu" signal "IN2")
		(12 "In5.Cu" signal "GND2")
		(14 "In6.Cu" signal "IN3")
		(16 "In7.Cu" signal "GND3")
		(18 "In8.Cu" signal "VCC")
		(20 "In9.Cu" signal "VCC1")
		(22 "In10.Cu" signal "GND4")
		(24 "In11.Cu" signal "IN4")
		(26 "In12.Cu" signal "GND5")
		(28 "In13.Cu" signal "IN5")
		(30 "In14.Cu" signal "GND6")
		(32 "In15.Cu" signal "IN6")
		(34 "In16.Cu" signal "GND7")
		(2 "B.Cu" signal "BOTTOM")
		(9 "F.Adhes" user "F.Adhesive")
		(11 "B.Adhes" user "B.Adhesive")
		(13 "F.Paste" user "Package Geometry/Pastemask Top")
		(15 "B.Paste" user "Package Geometry/Pastemask Bottom")
		(5 "F.SilkS" user "Ref Des/Silkscreen Top")
		(7 "B.SilkS" user "Ref Des/Silkscreen Bottom")
		(1 "F.Mask" user "Board Geometry/Soldermask Top")
		(3 "B.Mask" user "Board Geometry/Soldermask Bottom")
		(17 "Dwgs.User" user "User.Drawings")
		(19 "Cmts.User" user "User.Comments")
		(21 "Eco1.User" user "User.Eco1")
		(23 "Eco2.User" user "User.Eco2")
		(25 "Edge.Cuts" user "Board Geometry/Outline")
		(27 "Margin" user)
		(31 "F.CrtYd" user "Package Geometry/Place Bound Top")
		(29 "B.CrtYd" user "Package Geometry/Place Bound Bottom")
		(35 "F.Fab" user "Ref Des/Assembly Top")
		(33 "B.Fab" user "Ref Des/Assembly Bottom")
	)
	(footprint ""
		(layer "F.Cu")
		(at 157.08884 -31.341568 -90)
		(property "Reference" "R4466"
			(at 0 0 270)
			(layer "F.SilkS")
			(hide yes)
			(effects
				(font
					(size 1.27 1.27)
				)
			)
		)
		(property "Value" ""
			(at 0 0 270)
			(layer "F.Fab")
			(effects
				(font
					(size 1.27 1.27)
				)
			)
		)
		(duplicate_pad_numbers_are_jumpers no)
		(fp_line
			(start -0.7874 0.4064)
			(end -0.7874 -0.4064)
			(stroke
				(width 0.1524)
				(type default)
			)
			(layer "F.SilkS")
		)
		(fp_line
			(start 0.7874 0.4064)
			(end -0.7874 0.4064)
			(stroke
				(width 0.1524)
				(type default)
			)
			(layer "F.SilkS")
		)
		(fp_line
			(start -0.7874 -0.4064)
			(end 0.7874 -0.4064)
			(stroke
				(width 0.1524)
				(type default)
			)
			(layer "F.SilkS")
		)
		(fp_line
			(start 0.7874 -0.4064)
			(end 0.7874 0.4064)
			(stroke
				(width 0.1524)
				(type default)
			)
			(layer "F.SilkS")
		)
		(fp_line
			(start -0.67945 0.3048)
			(end -0.67945 -0.305054)
			(stroke
				(width 0.1)
				(type default)
			)
			(layer "F.Fab")
		)
		(fp_line
			(start -0.12065 0.3048)
			(end -0.67945 0.3048)
			(stroke
				(width 0.1)
				(type default)
			)
			(layer "F.Fab")
		)
		(fp_line
			(start 0.120396 0.3048)
			(end 0.120396 0.2794)
			(stroke
				(width 0.1)
				(type default)
			)
			(layer "F.Fab")
		)
		(fp_line
			(start 0.67945 0.3048)
			(end 0.120396 0.3048)
			(stroke
				(width 0.1)
				(type default)
			)
			(layer "F.Fab")
		)
		(fp_line
			(start -0.12065 0.2794)
			(end -0.12065 0.3048)
			(stroke
				(width 0.1)
				(type default)
			)
			(layer "F.Fab")
		)
		(fp_line
			(start 0.120396 0.2794)
			(end -0.12065 0.2794)
			(stroke
				(width 0.1)
				(type default)
			)
			(layer "F.Fab")
		)
		(fp_line
			(start -0.12065 -0.2794)
			(end 0.12065 -0.2794)
			(stroke
				(width 0.1)
				(type default)
			)
			(layer "F.Fab")
		)
		(fp_line
			(start 0.12065 -0.2794)
			(end 0.12065 -0.3048)
			(stroke
				(width 0.1)
				(type default)
			)
			(layer "F.Fab")
		)
		(fp_line
			(start 0.12065 -0.3048)
			(end 0.67945 -0.3048)
			(stroke
				(width 0.1)
				(type default)
			)
			(layer "F.Fab")
		)
		(fp_line
			(start 0.67945 -0.3048)
			(end 0.67945 0.3048)
			(stroke
				(width 0.1)
				(type default)
			)
			(layer "F.Fab")
		)
		(fp_line
			(start -0.67945 -0.305054)
			(end -0.12065 -0.305054)
			(stroke
				(width 0.1)
				(type default)
			)
			(layer "F.Fab")
		)
		(fp_line
			(start -0.12065 -0.305054)
			(end -0.12065 -0.2794)
			(stroke
				(width 0.1)
				(type default)
			)
			(layer "F.Fab")
		)
		(pad "1" smd circle
			(at -0.40005 0 270)
			(size 0 0)
			(layers "F.Cu" "F.Mask" "F.Paste")
			(net "USB_HUB_2_TEST")
		)
		(pad "2" smd circle
			(at 0.40005 0 270)
			(size 0 0)
			(layers "F.Cu" "F.Mask" "F.Paste")
			(net "GND")
		)
	)
	(footprint ""
		(layer "F.Cu")
		(at 377.52401 -402.371052 -90)
		(property "Reference" "C939"
			(at 0 0 270)
			(layer "F.SilkS")
			(hide yes)
			(effects
				(font
					(size 1.27 1.27)
				)
			)
		)
		(property "Value" ""
			(at 0 0 270)
			(layer "F.Fab")
			(effects
				(font
					(size 1.27 1.27)
				)
			)
		)
		(duplicate_pad_numbers_are_jumpers no)
		(fp_line
			(start -0.299974 0.150114)
			(end -0.299974 -0.150114)
			(stroke
				(width 0.1)
				(type default)
			)
			(layer "F.Fab")
		)
		(fp_line
			(start 0.299974 0.150114)
			(end -0.299974 0.150114)
			(stroke
				(width 0.1)
				(type default)
			)
			(layer "F.Fab")
		)
		(fp_line
			(start -0.299974 -0.150114)
			(end 0.299974 -0.150114)
			(stroke
				(width 0.1)
				(type default)
			)
			(layer "F.Fab")
		)
		(fp_line
			(start 0.299974 -0.150114)
			(end 0.299974 0.150114)
			(stroke
				(width 0.1)
				(type default)
			)
			(layer "F.Fab")
		)
		(pad "1" smd rect
			(at -0.2667 0 270)
			(size 0.3048 0.381)
			(layers "F.Cu" "F.Mask" "F.Paste")
			(net "P5E_CPU0_PE2_TX_C_DP<13>")
		)
		(pad "2" smd rect
			(at 0.2667 0 270)
			(size 0.3048 0.381)
			(layers "F.Cu" "F.Mask" "F.Paste")
			(net "P5E_CPU0_PE2_TX_DP<13>")
		)
	)
	(footprint ""
		(layer "F.Cu")
		(at 183.878982 -34.794952 90)
		(property "Reference" "PC2231"
			(at 0 0 90)
			(layer "F.SilkS")
			(hide yes)
			(effects
				(font
					(size 1.27 1.27)
				)
			)
		)
		(property "Value" ""
			(at 0 0 90)
			(layer "F.Fab")
			(effects
				(font
					(size 1.27 1.27)
				)
			)
		)
		(duplicate_pad_numbers_are_jumpers no)
		(fp_line
			(start 0.7874 -0.4064)
			(end 0.7874 0.4064)
			(stroke
				(width 0.1524)
				(type default)
			)
			(layer "F.SilkS")
		)
		(fp_line
			(start -0.7874 -0.4064)
			(end 0.7874 -0.4064)
			(stroke
				(width 0.1524)
				(type default)
			)
			(layer "F.SilkS")
		)
		(fp_line
			(start 0.7874 0.4064)
			(end -0.7874 0.4064)
			(stroke
				(width 0.1524)
				(type default)
			)
			(layer "F.SilkS")
		)
		(fp_line
			(start -0.7874 0.4064)
			(end -0.7874 -0.4064)
			(stroke
				(width 0.1524)
				(type default)
			)
			(layer "F.SilkS")
		)
		(fp_line
			(start -0.12065 -0.305054)
			(end -0.12065 -0.2794)
			(stroke
				(width 0.1)
				(type default)
			)
			(layer "F.Fab")
		)
		(fp_line
			(start -0.67945 -0.305054)
			(end -0.12065 -0.305054)
			(stroke
				(width 0.1)
				(type default)
			)
			(layer "F.Fab")
		)
		(fp_line
			(start 0.67945 -0.3048)
			(end 0.67945 0.3048)
			(stroke
				(width 0.1)
				(type default)
			)
			(layer "F.Fab")
		)
		(fp_line
			(start 0.12065 -0.3048)
			(end 0.67945 -0.3048)
			(stroke
				(width 0.1)
				(type default)
			)
			(layer "F.Fab")
		)
		(fp_line
			(start 0.12065 -0.2794)
			(end 0.12065 -0.3048)
			(stroke
				(width 0.1)
				(type default)
			)
			(layer "F.Fab")
		)
		(fp_line
			(start -0.12065 -0.2794)
			(end 0.12065 -0.2794)
			(stroke
				(width 0.1)
				(type default)
			)
			(layer "F.Fab")
		)
		(fp_line
			(start 0.120396 0.2794)
			(end -0.12065 0.2794)
			(stroke
				(width 0.1)
				(type default)
			)
			(layer "F.Fab")
		)
		(fp_line
			(start -0.12065 0.2794)
			(end -0.12065 0.3048)
			(stroke
				(width 0.1)
				(type default)
			)
			(layer "F.Fab")
		)
		(fp_line
			(start 0.67945 0.3048)
			(end 0.120396 0.3048)
			(stroke
				(width 0.1)
				(type default)
			)
			(layer "F.Fab")
		)
		(fp_line
			(start 0.120396 0.3048)
			(end 0.120396 0.2794)
			(stroke
				(width 0.1)
				(type default)
			)
			(layer "F.Fab")
		)
		(fp_line
			(start -0.12065 0.3048)
			(end -0.67945 0.3048)
			(stroke
				(width 0.1)
				(type default)
			)
			(layer "F.Fab")
		)
		(fp_line
			(start -0.67945 0.3048)
			(end -0.67945 -0.305054)
			(stroke
				(width 0.1)
				(type default)
			)
			(layer "F.Fab")
		)
		(pad "1" smd circle
			(at -0.40005 0 90)
			(size 0 0)
			(layers "F.Cu" "F.Mask" "F.Paste")
			(net "P12V_AUX")
		)
		(pad "2" smd circle
			(at 0.40005 0 90)
			(size 0 0)
			(layers "F.Cu" "F.Mask" "F.Paste")
			(net "GND")
		)
	)
	(footprint ""
		(layer "F.Cu")
		(at 113.349024 -324.445376)
		(property "Reference" "PL29"
			(at 15.954756 6.788658 0)
			(unlocked yes)
			(layer "F.SilkS")
			(effects
				(font
					(size 0.7874 0.5842)
					(thickness 0.1524)
				)
				(justify left)
			)
		)
		(property "Value" ""
			(at 0 0 0)
			(layer "F.Fab")
			(effects
				(font
					(size 1.27 1.27)
				)
			)
		)
		(duplicate_pad_numbers_are_jumpers no)
		(fp_line
			(start -3.750056 -5.500116)
			(end -2.393442 -5.500116)
			(stroke
				(width 0.1524)
				(type default)
			)
			(layer "F.SilkS")
		)
		(fp_line
			(start -3.750056 5.500116)
			(end -3.750056 -5.500116)
			(stroke
				(width 0.1524)
				(type default)
			)
			(layer "F.SilkS")
		)
		(fp_line
			(start -2.393442 5.500116)
			(end -3.750056 5.500116)
			(stroke
				(width 0.1524)
				(type default)
			)
			(layer "F.SilkS")
		)
		(fp_line
			(start 2.393442 5.500116)
			(end 3.750056 5.500116)
			(stroke
				(width 0.1524)
				(type default)
			)
			(layer "F.SilkS")
		)
		(fp_line
			(start 3.750056 -5.500116)
			(end 2.393442 -5.500116)
			(stroke
				(width 0.1524)
				(type default)
			)
			(layer "F.SilkS")
		)
		(fp_line
			(start 3.750056 5.500116)
			(end 3.750056 -5.500116)
			(stroke
				(width 0.1524)
				(type default)
			)
			(layer "F.SilkS")
		)
		(fp_poly
			(pts
				(xy -3.554476 -7.016496) (xy -3.19532 -5.938774) (xy -4.273042 -6.29793)
			)
			(stroke
				(width 0)
				(type default)
			)
			(fill yes)
			(layer "F.SilkS")
		)
		(fp_line
			(start -3.750056 -5.500116)
			(end -3.750056 5.500116)
			(stroke
				(width 0.1)
				(type default)
			)
			(layer "F.Fab")
		)
		(fp_line
			(start -3.750056 5.500116)
			(end 3.750056 5.500116)
			(stroke
				(width 0.1)
				(type default)
			)
			(layer "F.Fab")
		)
		(fp_line
			(start 3.750056 -5.500116)
			(end -3.750056 -5.500116)
			(stroke
				(width 0.1)
				(type default)
			)
			(layer "F.Fab")
		)
		(fp_line
			(start 3.750056 5.500116)
			(end 3.750056 -5.500116)
			(stroke
				(width 0.1)
				(type default)
			)
			(layer "F.Fab")
		)
		(fp_poly
			(pts
				(xy -4.9276 -4.757928) (xy -4.9276 -3.741928) (xy -3.9116 -4.249928)
			)
			(stroke
				(width 0)
				(type default)
			)
			(fill yes)
			(layer "F.Fab")
		)
		(pad "1" smd rect
			(at 0 -4.249928 270)
			(size 2.413 4.5212)
			(layers "F.Cu" "F.Mask" "F.Paste")
			(net "SW_PVCCIN_CPU1_SW3")
		)
		(pad "2" smd rect
			(at 0 -1.175004 270)
			(size 1.3716 4.5212)
			(layers "F.Cu" "F.Mask" "F.Paste")
			(net "IND_P1_CPL3")
		)
		(pad "3" smd rect
			(at 0 1.175004 270)
			(size 1.3716 4.5212)
			(layers "F.Cu" "F.Mask" "F.Paste")
			(net "IND_P1_CPL2")
		)
		(pad "4" smd rect
			(at 0 4.249928 270)
			(size 2.413 4.5212)
			(layers "F.Cu" "F.Mask" "F.Paste")
			(net "PVCCIN_CPU1")
		)
	)
	(footprint ""
		(layer "F.Cu")
		(at 149.68982 -22.73808 90)
		(property "Reference" "R3778"
			(at 0 0 90)
			(layer "F.SilkS")
			(hide yes)
			(effects
				(font
					(size 1.27 1.27)
				)
			)
		)
		(property "Value" ""
			(at 0 0 90)
			(layer "F.Fab")
			(effects
				(font
					(size 1.27 1.27)
				)
			)
		)
		(duplicate_pad_numbers_are_jumpers no)
		(fp_line
			(start 0.7874 -0.4064)
			(end 0.7874 0.4064)
			(stroke
				(width 0.1524)
				(type default)
			)
			(layer "F.SilkS")
		)
		(fp_line
			(start -0.7874 -0.4064)
			(end 0.7874 -0.4064)
			(stroke
				(width 0.1524)
				(type default)
			)
			(layer "F.SilkS")
		)
		(fp_line
			(start 0.7874 0.4064)
			(end -0.7874 0.4064)
			(stroke
				(width 0.1524)
				(type default)
			)
			(layer "F.SilkS")
		)
		(fp_line
			(start -0.7874 0.4064)
			(end -0.7874 -0.4064)
			(stroke
				(width 0.1524)
				(type default)
			)
			(layer "F.SilkS")
		)
		(fp_line
			(start -0.12065 -0.305054)
			(end -0.12065 -0.2794)
			(stroke
				(width 0.1)
				(type default)
			)
			(layer "F.Fab")
		)
		(fp_line
			(start -0.67945 -0.305054)
			(end -0.12065 -0.305054)
			(stroke
				(width 0.1)
				(type default)
			)
			(layer "F.Fab")
		)
		(fp_line
			(start 0.67945 -0.3048)
			(end 0.67945 0.3048)
			(stroke
				(width 0.1)
				(type default)
			)
			(layer "F.Fab")
		)
		(fp_line
			(start 0.12065 -0.3048)
			(end 0.67945 -0.3048)
			(stroke
				(width 0.1)
				(type default)
			)
			(layer "F.Fab")
		)
		(fp_line
			(start 0.12065 -0.2794)
			(end 0.12065 -0.3048)
			(stroke
				(width 0.1)
				(type default)
			)
			(layer "F.Fab")
		)
		(fp_line
			(start -0.12065 -0.2794)
			(end 0.12065 -0.2794)
			(stroke
				(width 0.1)
				(type default)
			)
			(layer "F.Fab")
		)
		(fp_line
			(start 0.120396 0.2794)
			(end -0.12065 0.2794)
			(stroke
				(width 0.1)
				(type default)
			)
			(layer "F.Fab")
		)
		(fp_line
			(start -0.12065 0.2794)
			(end -0.12065 0.3048)
			(stroke
				(width 0.1)
				(type default)
			)
			(layer "F.Fab")
		)
		(fp_line
			(start 0.67945 0.3048)
			(end 0.120396 0.3048)
			(stroke
				(width 0.1)
				(type default)
			)
			(layer "F.Fab")
		)
		(fp_line
			(start 0.120396 0.3048)
			(end 0.120396 0.2794)
			(stroke
				(width 0.1)
				(type default)
			)
			(layer "F.Fab")
		)
		(fp_line
			(start -0.12065 0.3048)
			(end -0.67945 0.3048)
			(stroke
				(width 0.1)
				(type default)
			)
			(layer "F.Fab")
		)
		(fp_line
			(start -0.67945 0.3048)
			(end -0.67945 -0.305054)
			(stroke
				(width 0.1)
				(type default)
			)
			(layer "F.Fab")
		)
		(pad "1" smd circle
			(at -0.40005 0 90)
			(size 0 0)
			(layers "F.Cu" "F.Mask" "F.Paste")
			(net "FM_SOL_UART_CH_SEL_R")
		)
		(pad "2" smd circle
			(at 0.40005 0 90)
			(size 0 0)
			(layers "F.Cu" "F.Mask" "F.Paste")
			(net "FM_SOL_UART_CH_SEL")
		)
	)
	(footprint ""
		(layer "F.Cu")
		(at 356.616 -417.159948 180)
		(property "Reference" "R4559"
			(at 0 0 180)
			(layer "F.SilkS")
			(hide yes)
			(effects
				(font
					(size 1.27 1.27)
				)
			)
		)
		(property "Value" ""
			(at 0 0 180)
			(layer "F.Fab")
			(effects
				(font
					(size 1.27 1.27)
				)
			)
		)
		(duplicate_pad_numbers_are_jumpers no)
		(fp_line
			(start 0.7874 0.4064)
			(end -0.7874 0.4064)
			(stroke
				(width 0.1524)
				(type default)
			)
			(layer "F.SilkS")
		)
		(fp_line
			(start 0.7874 -0.4064)
			(end 0.7874 0.4064)
			(stroke
				(width 0.1524)
				(type default)
			)
			(layer "F.SilkS")
		)
		(fp_line
			(start -0.7874 0.4064)
			(end -0.7874 -0.4064)
			(stroke
				(width 0.1524)
				(type default)
			)
			(layer "F.SilkS")
		)
		(fp_line
			(start -0.7874 -0.4064)
			(end 0.7874 -0.4064)
			(stroke
				(width 0.1524)
				(type default)
			)
			(layer "F.SilkS")
		)
		(fp_line
			(start 0.67945 0.3048)
			(end 0.120396 0.3048)
			(stroke
				(width 0.1)
				(type default)
			)
			(layer "F.Fab")
		)
		(fp_line
			(start 0.67945 -0.3048)
			(end 0.67945 0.3048)
			(stroke
				(width 0.1)
				(type default)
			)
			(layer "F.Fab")
		)
		(fp_line
			(start 0.12065 -0.2794)
			(end 0.12065 -0.3048)
			(stroke
				(width 0.1)
				(type default)
			)
			(layer "F.Fab")
		)
		(fp_line
			(start 0.12065 -0.3048)
			(end 0.67945 -0.3048)
			(stroke
				(width 0.1)
				(type default)
			)
			(layer "F.Fab")
		)
		(fp_line
			(start 0.120396 0.3048)
			(end 0.120396 0.2794)
			(stroke
				(width 0.1)
				(type default)
			)
			(layer "F.Fab")
		)
		(fp_line
			(start 0.120396 0.2794)
			(end -0.12065 0.2794)
			(stroke
				(width 0.1)
				(type default)
			)
			(layer "F.Fab")
		)
		(fp_line
			(start -0.12065 0.3048)
			(end -0.67945 0.3048)
			(stroke
				(width 0.1)
				(type default)
			)
			(layer "F.Fab")
		)
		(fp_line
			(start -0.12065 0.2794)
			(end -0.12065 0.3048)
			(stroke
				(width 0.1)
				(type default)
			)
			(layer "F.Fab")
		)
		(fp_line
			(start -0.12065 -0.2794)
			(end 0.12065 -0.2794)
			(stroke
				(width 0.1)
				(type default)
			)
			(layer "F.Fab")
		)
		(fp_line
			(start -0.12065 -0.305054)
			(end -0.12065 -0.2794)
			(stroke
				(width 0.1)
				(type default)
			)
			(layer "F.Fab")
		)
		(fp_line
			(start -0.67945 0.3048)
			(end -0.67945 -0.305054)
			(stroke
				(width 0.1)
				(type default)
			)
			(layer "F.Fab")
		)
		(fp_line
			(start -0.67945 -0.305054)
			(end -0.12065 -0.305054)
			(stroke
				(width 0.1)
				(type default)
			)
			(layer "F.Fab")
		)
		(pad "1" smd circle
			(at -0.40005 0 180)
			(size 0 0)
			(layers "F.Cu" "F.Mask" "F.Paste")
			(net "SWB_HSC_PWRGD")
		)
		(pad "2" smd circle
			(at 0.40005 0 180)
			(size 0 0)
			(layers "F.Cu" "F.Mask" "F.Paste")
			(net "GND")
		)
	)
	(footprint ""
		(layer "F.Cu")
		(at 422.509188 -154.251914 180)
		(property "Reference" "PC1348"
			(at 0 0 180)
			(layer "F.SilkS")
			(hide yes)
			(effects
				(font
					(size 1.27 1.27)
				)
			)
		)
		(property "Value" ""
			(at 0 0 180)
			(layer "F.Fab")
			(effects
				(font
					(size 1.27 1.27)
				)
			)
		)
		(duplicate_pad_numbers_are_jumpers no)
		(fp_line
			(start 0.7874 0.4064)
			(end -0.7874 0.4064)
			(stroke
				(width 0.1524)
				(type default)
			)
			(layer "F.SilkS")
		)
		(fp_line
			(start 0.7874 -0.4064)
			(end 0.7874 0.4064)
			(stroke
				(width 0.1524)
				(type default)
			)
			(layer "F.SilkS")
		)
		(fp_line
			(start -0.7874 0.4064)
			(end -0.7874 -0.4064)
			(stroke
				(width 0.1524)
				(type default)
			)
			(layer "F.SilkS")
		)
		(fp_line
			(start -0.7874 -0.4064)
			(end 0.7874 -0.4064)
			(stroke
				(width 0.1524)
				(type default)
			)
			(layer "F.SilkS")
		)
		(fp_line
			(start 0.67945 0.3048)
			(end 0.120396 0.3048)
			(stroke
				(width 0.1)
				(type default)
			)
			(layer "F.Fab")
		)
		(fp_line
			(start 0.67945 -0.3048)
			(end 0.67945 0.3048)
			(stroke
				(width 0.1)
				(type default)
			)
			(layer "F.Fab")
		)
		(fp_line
			(start 0.12065 -0.2794)
			(end 0.12065 -0.3048)
			(stroke
				(width 0.1)
				(type default)
			)
			(layer "F.Fab")
		)
		(fp_line
			(start 0.12065 -0.3048)
			(end 0.67945 -0.3048)
			(stroke
				(width 0.1)
				(type default)
			)
			(layer "F.Fab")
		)
		(fp_line
			(start 0.120396 0.3048)
			(end 0.120396 0.2794)
			(stroke
				(width 0.1)
				(type default)
			)
			(layer "F.Fab")
		)
		(fp_line
			(start 0.120396 0.2794)
			(end -0.12065 0.2794)
			(stroke
				(width 0.1)
				(type default)
			)
			(layer "F.Fab")
		)
		(fp_line
			(start -0.12065 0.3048)
			(end -0.67945 0.3048)
			(stroke
				(width 0.1)
				(type default)
			)
			(layer "F.Fab")
		)
		(fp_line
			(start -0.12065 0.2794)
			(end -0.12065 0.3048)
			(stroke
				(width 0.1)
				(type default)
			)
			(layer "F.Fab")
		)
		(fp_line
			(start -0.12065 -0.2794)
			(end 0.12065 -0.2794)
			(stroke
				(width 0.1)
				(type default)
			)
			(layer "F.Fab")
		)
		(fp_line
			(start -0.12065 -0.305054)
			(end -0.12065 -0.2794)
			(stroke
				(width 0.1)
				(type default)
			)
			(layer "F.Fab")
		)
		(fp_line
			(start -0.67945 0.3048)
			(end -0.67945 -0.305054)
			(stroke
				(width 0.1)
				(type default)
			)
			(layer "F.Fab")
		)
		(fp_line
			(start -0.67945 -0.305054)
			(end -0.12065 -0.305054)
			(stroke
				(width 0.1)
				(type default)
			)
			(layer "F.Fab")
		)
		(pad "1" smd circle
			(at -0.40005 0 180)
			(size 0 0)
			(layers "F.Cu" "F.Mask" "F.Paste")
			(net "GND")
		)
		(pad "2" smd circle
			(at 0.40005 0 180)
			(size 0 0)
			(layers "F.Cu" "F.Mask" "F.Paste")
			(net "PVCCINFAON_CPU0_VREF")
		)
	)
)
